# S9S_MB_2U (Grand Teton) — schematic netlist excerpt (pin names and nets, part order shuffled) for the footprints in the layout excerpt that follows; sources: Cadence DE-HDL packaged netlist, KiCad conversion of 03242023_DA0F0TMBIJ0_F0T_Motherboard_J_brd_V01_OCP.brd

R2996  Q_RES  33.2 1% CHIP  pkg 0402LF  page 241 : A = SMB_SML1_PMBUS_3V3AUX_PCH_SDA ; B = SMB_SML1_PMBUS_HSC_SDA_R3
PC1362  Q_CAP  0.1UF 25V 10% X7R  pkg 0402  page 288 : A = GND ; B = PVCCIN_CPU1_VREF

(kicad_pcb
	(version 20260206)
	(generator "pcbnew")
	(generator_version "10.0")
	(general
		(thickness 1.6)
		(legacy_teardrops no)
	)
	(paper "A4")
	(title_block
		(title "03242023_DA0F0TMBIJ0_F0T_Motherboard_J_brd_V01_OCP.brd")
		(comment 1 "Grand Teton / footprints 2926-2927 of 6105")
	)
	(layers
		(0 "F.Cu" signal "TOP")
		(4 "In1.Cu" signal "GND")
		(6 "In2.Cu" signal "IN1")
		(8 "In3.Cu" signal "GND1")
		(10 "In4.Cu" signal "IN2")
		(12 "In5.Cu" signal "GND2")
		(14 "In6.Cu" signal "IN3")
		(16 "In7.Cu" signal "GND3")
		(18 "In8.Cu" signal "VCC")
		(20 "In9.Cu" signal "VCC1")
		(22 "In10.Cu" signal "GND4")
		(24 "In11.Cu" signal "IN4")
		(26 "In12.Cu" signal "GND5")
		(28 "In13.Cu" signal "IN5")
		(30 "In14.Cu" signal "GND6")
		(32 "In15.Cu" signal "IN6")
		(34 "In16.Cu" signal "GND7")
		(2 "B.Cu" signal "BOTTOM")
		(9 "F.Adhes" user "F.Adhesive")
		(11 "B.Adhes" user "B.Adhesive")
		(13 "F.Paste" user "Package Geometry/Pastemask Top")
		(15 "B.Paste" user "Package Geometry/Pastemask Bottom")
		(5 "F.SilkS" user "Ref Des/Silkscreen Top")
		(7 "B.SilkS" user "Ref Des/Silkscreen Bottom")
		(1 "F.Mask" user "Board Geometry/Soldermask Top")
		(3 "B.Mask" user "Board Geometry/Soldermask Bottom")
		(17 "Dwgs.User" user "User.Drawings")
		(19 "Cmts.User" user "User.Comments")
		(21 "Eco1.User" user "User.Eco1")
		(23 "Eco2.User" user "User.Eco2")
		(25 "Edge.Cuts" user "Board Geometry/Outline")
		(27 "Margin" user)
		(31 "F.CrtYd" user "Package Geometry/Place Bound Top")
		(29 "B.CrtYd" user "Package Geometry/Place Bound Bottom")
		(35 "F.Fab" user "Ref Des/Assembly Top")
		(33 "B.Fab" user "Ref Des/Assembly Bottom")
	)
	(footprint ""
		(layer "F.Cu")
		(at 7.42188 -54.955948)
		(property "Reference" "R2996"
			(at 0 0 0)
			(layer "F.SilkS")
			(hide yes)
			(effects
				(font
					(size 1.27 1.27)
				)
			)
		)
		(property "Value" ""
			(at 0 0 0)
			(layer "F.Fab")
			(effects
				(font
					(size 1.27 1.27)
				)
			)
		)
		(duplicate_pad_numbers_are_jumpers no)
		(fp_line
			(start -0.7874 -0.4064)
			(end 0.7874 -0.4064)
			(stroke
				(width 0.1524)
				(type default)
			)
			(layer "F.SilkS")
		)
		(fp_line
			(start -0.7874 0.4064)
			(end -0.7874 -0.4064)
			(stroke
				(width 0.1524)
				(type default)
			)
			(layer "F.SilkS")
		)
		(fp_line
			(start 0.7874 -0.4064)
			(end 0.7874 0.4064)
			(stroke
				(width 0.1524)
				(type default)
			)
			(layer "F.SilkS")
		)
		(fp_line
			(start 0.7874 0.4064)
			(end -0.7874 0.4064)
			(stroke
				(width 0.1524)
				(type default)
			)
			(layer "F.SilkS")
		)
		(fp_line
			(start -0.67945 -0.305054)
			(end -0.12065 -0.305054)
			(stroke
				(width 0.1)
				(type default)
			)
			(layer "F.Fab")
		)
		(fp_line
			(start -0.67945 0.3048)
			(end -0.67945 -0.305054)
			(stroke
				(width 0.1)
				(type default)
			)
			(layer "F.Fab")
		)
		(fp_line
			(start -0.12065 -0.305054)
			(end -0.12065 -0.2794)
			(stroke
				(width 0.1)
				(type default)
			)
			(layer "F.Fab")
		)
		(fp_line
			(start -0.12065 -0.2794)
			(end 0.12065 -0.2794)
			(stroke
				(width 0.1)
				(type default)
			)
			(layer "F.Fab")
		)
		(fp_line
			(start -0.12065 0.2794)
			(end -0.12065 0.3048)
			(stroke
				(width 0.1)
				(type default)
			)
			(layer "F.Fab")
		)
		(fp_line
			(start -0.12065 0.3048)
			(end -0.67945 0.3048)
			(stroke
				(width 0.1)
				(type default)
			)
			(layer "F.Fab")
		)
		(fp_line
			(start 0.120396 0.2794)
			(end -0.12065 0.2794)
			(stroke
				(width 0.1)
				(type default)
			)
			(layer "F.Fab")
		)
		(fp_line
			(start 0.120396 0.3048)
			(end 0.120396 0.2794)
			(stroke
				(width 0.1)
				(type default)
			)
			(layer "F.Fab")
		)
		(fp_line
			(start 0.12065 -0.3048)
			(end 0.67945 -0.3048)
			(stroke
				(width 0.1)
				(type default)
			)
			(layer "F.Fab")
		)
		(fp_line
			(start 0.12065 -0.2794)
			(end 0.12065 -0.3048)
			(stroke
				(width 0.1)
				(type default)
			)
			(layer "F.Fab")
		)
		(fp_line
			(start 0.67945 -0.3048)
			(end 0.67945 0.3048)
			(stroke
				(width 0.1)
				(type default)
			)
			(layer "F.Fab")
		)
		(fp_line
			(start 0.67945 0.3048)
			(end 0.120396 0.3048)
			(stroke
				(width 0.1)
				(type default)
			)
			(layer "F.Fab")
		)
		(pad "1" smd circle
			(at -0.40005 0)
			(size 0 0)
			(layers "F.Cu" "F.Mask" "F.Paste")
			(net "SMB_SML1_PMBUS_3V3AUX_PCH_SDA")
		)
		(pad "2" smd circle
			(at 0.40005 0)
			(size 0 0)
			(layers "F.Cu" "F.Mask" "F.Paste")
			(net "SMB_SML1_PMBUS_HSC_SDA_R3")
		)
	)
	(footprint ""
		(layer "F.Cu")
		(at 135.02894 -347.509846 -90)
		(property "Reference" "PC1362"
			(at 0 0 270)
			(layer "F.SilkS")
			(hide yes)
			(effects
				(font
					(size 1.27 1.27)
				)
			)
		)
		(property "Value" ""
			(at 0 0 270)
			(layer "F.Fab")
			(effects
				(font
					(size 1.27 1.27)
				)
			)
		)
		(duplicate_pad_numbers_are_jumpers no)
		(fp_line
			(start -0.7874 0.4064)
			(end -0.7874 -0.4064)
			(stroke
				(width 0.1524)
				(type default)
			)
			(layer "F.SilkS")
		)
		(fp_line
			(start 0.7874 0.4064)
			(end -0.7874 0.4064)
			(stroke
				(width 0.1524)
				(type default)
			)
			(layer "F.SilkS")
		)
		(fp_line
			(start -0.7874 -0.4064)
			(end 0.7874 -0.4064)
			(stroke
				(width 0.1524)
				(type default)
			)
			(layer "F.SilkS")
		)
		(fp_line
			(start 0.7874 -0.4064)
			(end 0.7874 0.4064)
			(stroke
				(width 0.1524)
				(type default)
			)
			(layer "F.SilkS")
		)
		(fp_line
			(start -0.67945 0.3048)
			(end -0.67945 -0.305054)
			(stroke
				(width 0.1)
				(type default)
			)
			(layer "F.Fab")
		)
		(fp_line
			(start -0.12065 0.3048)
			(end -0.67945 0.3048)
			(stroke
				(width 0.1)
				(type default)
			)
			(layer "F.Fab")
		)
		(fp_line
			(start 0.120396 0.3048)
			(end 0.120396 0.2794)
			(stroke
				(width 0.1)
				(type default)
			)
			(layer "F.Fab")
		)
		(fp_line
			(start 0.67945 0.3048)
			(end 0.120396 0.3048)
			(stroke
				(width 0.1)
				(type default)
			)
			(layer "F.Fab")
		)
		(fp_line
			(start -0.12065 0.2794)
			(end -0.12065 0.3048)
			(stroke
				(width 0.1)
				(type default)
			)
			(layer "F.Fab")
		)
		(fp_line
			(start 0.120396 0.2794)
			(end -0.12065 0.2794)
			(stroke
				(width 0.1)
				(type default)
			)
			(layer "F.Fab")
		)
		(fp_line
			(start -0.12065 -0.2794)
			(end 0.12065 -0.2794)
			(stroke
				(width 0.1)
				(type default)
			)
			(layer "F.Fab")
		)
		(fp_line
			(start 0.12065 -0.2794)
			(end 0.12065 -0.3048)
			(stroke
				(width 0.1)
				(type default)
			)
			(layer "F.Fab")
		)
		(fp_line
			(start 0.12065 -0.3048)
			(end 0.67945 -0.3048)
			(stroke
				(width 0.1)
				(type default)
			)
			(layer "F.Fab")
		)
		(fp_line
			(start 0.67945 -0.3048)
			(end 0.67945 0.3048)
			(stroke
				(width 0.1)
				(type default)
			)
			(layer "F.Fab")
		)
		(fp_line
			(start -0.67945 -0.305054)
			(end -0.12065 -0.305054)
			(stroke
				(width 0.1)
				(type default)
			)
			(layer "F.Fab")
		)
		(fp_line
			(start -0.12065 -0.305054)
			(end -0.12065 -0.2794)
			(stroke
				(width 0.1)
				(type default)
			)
			(layer "F.Fab")
		)
		(pad "1" smd circle
			(at -0.40005 0 270)
			(size 0 0)
			(layers "F.Cu" "F.Mask" "F.Paste")
			(net "GND")
		)
		(pad "2" smd circle
			(at 0.40005 0 270)
			(size 0 0)
			(layers "F.Cu" "F.Mask" "F.Paste")
			(net "PVCCIN_CPU1_VREF")
		)
	)
)
